# T6G (Grand Teton) — schematic netlist excerpt (pin names and nets, part order shuffled) for the footprints in the layout excerpt that follows; sources: Cadence DE-HDL packaged netlist, KiCad conversion of 04192023_DAF0TMB3IC0_F0TG_MB_C_brd_V02_OCP.brd

R3611  Q_RES  4.7K 1% CHIP  pkg 0402LF  page 237 : A = GND ; B = INA230_4_A0
PC401_C1P1_4  Q_CAP  2.2UF 10V 10% X6S  pkg C0402  page 219 : A = PVDDCR_CPU1_P1_PVCC ; B = GND

(kicad_pcb
	(version 20260206)
	(generator "pcbnew")
	(generator_version "10.0")
	(general
		(thickness 1.6)
		(legacy_teardrops no)
	)
	(paper "A4")
	(title_block
		(title "04192023_DAF0TMB3IC0_F0TG_MB_C_brd_V02_OCP.brd")
		(comment 1 "Grand Teton / footprints 2259-2260 of 8354")
	)
	(layers
		(0 "F.Cu" signal "TOP")
		(4 "In1.Cu" signal "GND")
		(6 "In2.Cu" signal "IN1")
		(8 "In3.Cu" signal "GND1")
		(10 "In4.Cu" signal "IN2")
		(12 "In5.Cu" signal "GND2")
		(14 "In6.Cu" signal "IN3")
		(16 "In7.Cu" signal "GND3")
		(18 "In8.Cu" signal "VCC")
		(20 "In9.Cu" signal "VCC1")
		(22 "In10.Cu" signal "GND4")
		(24 "In11.Cu" signal "IN4")
		(26 "In12.Cu" signal "GND5")
		(28 "In13.Cu" signal "IN5")
		(30 "In14.Cu" signal "GND6")
		(32 "In15.Cu" signal "IN6")
		(34 "In16.Cu" signal "GND7")
		(2 "B.Cu" signal "BOTTOM")
		(9 "F.Adhes" user "F.Adhesive")
		(11 "B.Adhes" user "B.Adhesive")
		(13 "F.Paste" user "Package Geometry/Pastemask Top")
		(15 "B.Paste" user "Package Geometry/Pastemask Bottom")
		(5 "F.SilkS" user "Ref Des/Silkscreen Top")
		(7 "B.SilkS" user "Ref Des/Silkscreen Bottom")
		(1 "F.Mask" user "Board Geometry/Soldermask Top")
		(3 "B.Mask" user "Board Geometry/Soldermask Bottom")
		(17 "Dwgs.User" user "User.Drawings")
		(19 "Cmts.User" user "User.Comments")
		(21 "Eco1.User" user "User.Eco1")
		(23 "Eco2.User" user "User.Eco2")
		(25 "Edge.Cuts" user "Board Geometry/Outline")
		(27 "Margin" user)
		(31 "F.CrtYd" user "Package Geometry/Place Bound Top")
		(29 "B.CrtYd" user "Package Geometry/Place Bound Bottom")
		(35 "F.Fab" user "Ref Des/Assembly Top")
		(33 "B.Fab" user "Ref Des/Assembly Bottom")
	)
	(footprint ""
		(layer "F.Cu")
		(at 58.191654 -346.719398 -90)
		(property "Reference" "PC401_C1P1_4"
			(at 0 0 270)
			(layer "F.SilkS")
			(hide yes)
			(effects
				(font
					(size 1.27 1.27)
				)
			)
		)
		(property "Value" ""
			(at 0 0 270)
			(layer "F.Fab")
			(effects
				(font
					(size 1.27 1.27)
				)
			)
		)
		(duplicate_pad_numbers_are_jumpers no)
		(fp_line
			(start -0.7874 0.4064)
			(end -0.7874 -0.4064)
			(stroke
				(width 0.1524)
				(type default)
			)
			(layer "F.SilkS")
		)
		(fp_line
			(start 0.7874 0.4064)
			(end -0.7874 0.4064)
			(stroke
				(width 0.1524)
				(type default)
			)
			(layer "F.SilkS")
		)
		(fp_line
			(start -0.7874 -0.4064)
			(end 0.7874 -0.4064)
			(stroke
				(width 0.1524)
				(type default)
			)
			(layer "F.SilkS")
		)
		(fp_line
			(start 0.7874 -0.4064)
			(end 0.7874 0.4064)
			(stroke
				(width 0.1524)
				(type default)
			)
			(layer "F.SilkS")
		)
		(fp_line
			(start -0.67945 0.3048)
			(end -0.67945 -0.305054)
			(stroke
				(width 0.1)
				(type default)
			)
			(layer "F.Fab")
		)
		(fp_line
			(start -0.12065 0.3048)
			(end -0.67945 0.3048)
			(stroke
				(width 0.1)
				(type default)
			)
			(layer "F.Fab")
		)
		(fp_line
			(start 0.120396 0.3048)
			(end 0.120396 0.2794)
			(stroke
				(width 0.1)
				(type default)
			)
			(layer "F.Fab")
		)
		(fp_line
			(start 0.67945 0.3048)
			(end 0.120396 0.3048)
			(stroke
				(width 0.1)
				(type default)
			)
			(layer "F.Fab")
		)
		(fp_line
			(start -0.12065 0.2794)
			(end -0.12065 0.3048)
			(stroke
				(width 0.1)
				(type default)
			)
			(layer "F.Fab")
		)
		(fp_line
			(start 0.120396 0.2794)
			(end -0.12065 0.2794)
			(stroke
				(width 0.1)
				(type default)
			)
			(layer "F.Fab")
		)
		(fp_line
			(start -0.12065 -0.2794)
			(end 0.12065 -0.2794)
			(stroke
				(width 0.1)
				(type default)
			)
			(layer "F.Fab")
		)
		(fp_line
			(start 0.12065 -0.2794)
			(end 0.12065 -0.3048)
			(stroke
				(width 0.1)
				(type default)
			)
			(layer "F.Fab")
		)
		(fp_line
			(start 0.12065 -0.3048)
			(end 0.67945 -0.3048)
			(stroke
				(width 0.1)
				(type default)
			)
			(layer "F.Fab")
		)
		(fp_line
			(start 0.67945 -0.3048)
			(end 0.67945 0.3048)
			(stroke
				(width 0.1)
				(type default)
			)
			(layer "F.Fab")
		)
		(fp_line
			(start -0.67945 -0.305054)
			(end -0.12065 -0.305054)
			(stroke
				(width 0.1)
				(type default)
			)
			(layer "F.Fab")
		)
		(fp_line
			(start -0.12065 -0.305054)
			(end -0.12065 -0.2794)
			(stroke
				(width 0.1)
				(type default)
			)
			(layer "F.Fab")
		)
		(pad "1" smd circle
			(at -0.40005 0 270)
			(size 0 0)
			(layers "F.Cu" "F.Mask" "F.Paste")
			(net "PVDDCR_CPU1_P1_PVCC")
		)
		(pad "2" smd circle
			(at 0.40005 0 270)
			(size 0 0)
			(layers "F.Cu" "F.Mask" "F.Paste")
			(net "GND")
		)
	)
	(footprint ""
		(layer "F.Cu")
		(at 150.502366 -56.204358)
		(property "Reference" "R3611"
			(at 0 0 0)
			(layer "F.SilkS")
			(hide yes)
			(effects
				(font
					(size 1.27 1.27)
				)
			)
		)
		(property "Value" ""
			(at 0 0 0)
			(layer "F.Fab")
			(effects
				(font
					(size 1.27 1.27)
				)
			)
		)
		(duplicate_pad_numbers_are_jumpers no)
		(fp_line
			(start -0.7874 -0.4064)
			(end 0.7874 -0.4064)
			(stroke
				(width 0.1524)
				(type default)
			)
			(layer "F.SilkS")
		)
		(fp_line
			(start -0.7874 0.4064)
			(end -0.7874 -0.4064)
			(stroke
				(width 0.1524)
				(type default)
			)
			(layer "F.SilkS")
		)
		(fp_line
			(start 0.7874 -0.4064)
			(end 0.7874 0.4064)
			(stroke
				(width 0.1524)
				(type default)
			)
			(layer "F.SilkS")
		)
		(fp_line
			(start 0.7874 0.4064)
			(end -0.7874 0.4064)
			(stroke
				(width 0.1524)
				(type default)
			)
			(layer "F.SilkS")
		)
		(fp_line
			(start -0.67945 -0.305054)
			(end -0.12065 -0.305054)
			(stroke
				(width 0.1)
				(type default)
			)
			(layer "F.Fab")
		)
		(fp_line
			(start -0.67945 0.3048)
			(end -0.67945 -0.305054)
			(stroke
				(width 0.1)
				(type default)
			)
			(layer "F.Fab")
		)
		(fp_line
			(start -0.12065 -0.305054)
			(end -0.12065 -0.2794)
			(stroke
				(width 0.1)
				(type default)
			)
			(layer "F.Fab")
		)
		(fp_line
			(start -0.12065 -0.2794)
			(end 0.12065 -0.2794)
			(stroke
				(width 0.1)
				(type default)
			)
			(layer "F.Fab")
		)
		(fp_line
			(start -0.12065 0.2794)
			(end -0.12065 0.3048)
			(stroke
				(width 0.1)
				(type default)
			)
			(layer "F.Fab")
		)
		(fp_line
			(start -0.12065 0.3048)
			(end -0.67945 0.3048)
			(stroke
				(width 0.1)
				(type default)
			)
			(layer "F.Fab")
		)
		(fp_line
			(start 0.120396 0.2794)
			(end -0.12065 0.2794)
			(stroke
				(width 0.1)
				(type default)
			)
			(layer "F.Fab")
		)
		(fp_line
			(start 0.120396 0.3048)
			(end 0.120396 0.2794)
			(stroke
				(width 0.1)
				(type default)
			)
			(layer "F.Fab")
		)
		(fp_line
			(start 0.12065 -0.3048)
			(end 0.67945 -0.3048)
			(stroke
				(width 0.1)
				(type default)
			)
			(layer "F.Fab")
		)
		(fp_line
			(start 0.12065 -0.2794)
			(end 0.12065 -0.3048)
			(stroke
				(width 0.1)
				(type default)
			)
			(layer "F.Fab")
		)
		(fp_line
			(start 0.67945 -0.3048)
			(end 0.67945 0.3048)
			(stroke
				(width 0.1)
				(type default)
			)
			(layer "F.Fab")
		)
		(fp_line
			(start 0.67945 0.3048)
			(end 0.120396 0.3048)
			(stroke
				(width 0.1)
				(type default)
			)
			(layer "F.Fab")
		)
		(pad "1" smd circle
			(at -0.40005 0)
			(size 0 0)
			(layers "F.Cu" "F.Mask" "F.Paste")
			(net "GND")
		)
		(pad "2" smd circle
			(at 0.40005 0)
			(size 0 0)
			(layers "F.Cu" "F.Mask" "F.Paste")
			(net "INA230_4_A0")
		)
	)
)
